(kicad_pcb
	(version 20260206)
	(generator "pcbnew")
	(generator_version "10.0")
	(general
		(thickness 1.6)
		(legacy_teardrops no)
	)
	(paper "A4")
	(title_block
		(title "01162023_DA0F0TEBIF0_F0T_Expander_BD_F_brd_V02_OCP.brd")
		(comment 1 "Grand Teton / footprints 6342-6347 of 9728")
	)
	(layers
		(0 "F.Cu" signal "TOP")
		(4 "In1.Cu" signal "GND")
		(6 "In2.Cu" signal "VCC")
		(8 "In3.Cu" signal "VCC1")
		(10 "In4.Cu" signal "GND1")
		(12 "In5.Cu" signal "IN1")
		(14 "In6.Cu" signal "GND2")
		(16 "In7.Cu" signal "IN2")
		(18 "In8.Cu" signal "GND3")
		(20 "In9.Cu" signal "IN3")
		(22 "In10.Cu" signal "GND4")
		(24 "In11.Cu" signal "IN4")
		(26 "In12.Cu" signal "GND5")
		(28 "In13.Cu" signal "IN5")
		(30 "In14.Cu" signal "GND6")
		(32 "In15.Cu" signal "IN6")
		(34 "In16.Cu" signal "GND7")
		(2 "B.Cu" signal "BOTTOM")
		(9 "F.Adhes" user "F.Adhesive")
		(11 "B.Adhes" user "B.Adhesive")
		(13 "F.Paste" user "Package Geometry/Pastemask Top")
		(15 "B.Paste" user "Package Geometry/Pastemask Bottom")
		(5 "F.SilkS" user "Ref Des/Silkscreen Top")
		(7 "B.SilkS" user "Ref Des/Silkscreen Bottom")
		(1 "F.Mask" user "Board Geometry/Soldermask Top")
		(3 "B.Mask" user "Board Geometry/Soldermask Bottom")
		(17 "Dwgs.User" user "User.Drawings")
		(19 "Cmts.User" user "User.Comments")
		(21 "Eco1.User" user "User.Eco1")
		(23 "Eco2.User" user "User.Eco2")
		(25 "Edge.Cuts" user "Board Geometry/Outline")
		(27 "Margin" user)
		(31 "F.CrtYd" user "Package Geometry/Place Bound Top")
		(29 "B.CrtYd" user "Package Geometry/Place Bound Bottom")
		(35 "F.Fab" user "Ref Des/Assembly Top")
		(33 "B.Fab" user "Ref Des/Assembly Bottom")
	)
	(footprint ""
		(layer "F.Cu")
		(at 80.623664 -87.349076 -90)
		(property "Reference" "R97"
			(at 0 0 270)
			(layer "F.SilkS")
			(hide yes)
			(effects
				(font
					(size 1.27 1.27)
				)
			)
		)
		(property "Value" ""
			(at 0 0 270)
			(layer "F.Fab")
			(effects
				(font
					(size 1.27 1.27)
				)
			)
		)
		(duplicate_pad_numbers_are_jumpers no)
		(fp_line
			(start -0.7874 0.4064)
			(end -0.7874 -0.4064)
			(stroke
				(width 0.1524)
				(type default)
			)
			(layer "F.SilkS")
		)
		(fp_line
			(start 0.7874 0.4064)
			(end -0.7874 0.4064)
			(stroke
				(width 0.1524)
				(type default)
			)
			(layer "F.SilkS")
		)
		(fp_line
			(start -0.7874 -0.4064)
			(end 0.7874 -0.4064)
			(stroke
				(width 0.1524)
				(type default)
			)
			(layer "F.SilkS")
		)
		(fp_line
			(start 0.7874 -0.4064)
			(end 0.7874 0.4064)
			(stroke
				(width 0.1524)
				(type default)
			)
			(layer "F.SilkS")
		)
		(fp_line
			(start -0.67945 0.3048)
			(end -0.67945 -0.305054)
			(stroke
				(width 0.1)
				(type default)
			)
			(layer "F.Fab")
		)
		(fp_line
			(start -0.12065 0.3048)
			(end -0.67945 0.3048)
			(stroke
				(width 0.1)
				(type default)
			)
			(layer "F.Fab")
		)
		(fp_line
			(start 0.120396 0.3048)
			(end 0.120396 0.2794)
			(stroke
				(width 0.1)
				(type default)
			)
			(layer "F.Fab")
		)
		(fp_line
			(start 0.67945 0.3048)
			(end 0.120396 0.3048)
			(stroke
				(width 0.1)
				(type default)
			)
			(layer "F.Fab")
		)
		(fp_line
			(start -0.12065 0.2794)
			(end -0.12065 0.3048)
			(stroke
				(width 0.1)
				(type default)
			)
			(layer "F.Fab")
		)
		(fp_line
			(start 0.120396 0.2794)
			(end -0.12065 0.2794)
			(stroke
				(width 0.1)
				(type default)
			)
			(layer "F.Fab")
		)
		(fp_line
			(start -0.12065 -0.2794)
			(end 0.12065 -0.2794)
			(stroke
				(width 0.1)
				(type default)
			)
			(layer "F.Fab")
		)
		(fp_line
			(start 0.12065 -0.2794)
			(end 0.12065 -0.3048)
			(stroke
				(width 0.1)
				(type default)
			)
			(layer "F.Fab")
		)
		(fp_line
			(start 0.12065 -0.3048)
			(end 0.67945 -0.3048)
			(stroke
				(width 0.1)
				(type default)
			)
			(layer "F.Fab")
		)
		(fp_line
			(start 0.67945 -0.3048)
			(end 0.67945 0.3048)
			(stroke
				(width 0.1)
				(type default)
			)
			(layer "F.Fab")
		)
		(fp_line
			(start -0.67945 -0.305054)
			(end -0.12065 -0.305054)
			(stroke
				(width 0.1)
				(type default)
			)
			(layer "F.Fab")
		)
		(fp_line
			(start -0.12065 -0.305054)
			(end -0.12065 -0.2794)
			(stroke
				(width 0.1)
				(type default)
			)
			(layer "F.Fab")
		)
		(pad "1" smd circle
			(at -0.40005 0 270)
			(size 0 0)
			(layers "F.Cu" "F.Mask" "F.Paste")
			(net "RST_NIC1_PERST1_R_N")
		)
		(pad "2" smd circle
			(at 0.40005 0 270)
			(size 0 0)
			(layers "F.Cu" "F.Mask" "F.Paste")
			(net "RST_HP_NIC1_BUF_N")
		)
	)
	(footprint ""
		(layer "F.Cu")
		(at 177.929794 -171.661328 180)
		(property "Reference" "C882"
			(at 0 0 180)
			(layer "F.SilkS")
			(hide yes)
			(effects
				(font
					(size 1.27 1.27)
				)
			)
		)
		(property "Value" ""
			(at 0 0 180)
			(layer "F.Fab")
			(effects
				(font
					(size 1.27 1.27)
				)
			)
		)
		(duplicate_pad_numbers_are_jumpers no)
		(fp_line
			(start 0.7874 0.4064)
			(end -0.7874 0.4064)
			(stroke
				(width 0.1524)
				(type default)
			)
			(layer "F.SilkS")
		)
		(fp_line
			(start 0.7874 -0.4064)
			(end 0.7874 0.4064)
			(stroke
				(width 0.1524)
				(type default)
			)
			(layer "F.SilkS")
		)
		(fp_line
			(start -0.7874 0.4064)
			(end -0.7874 -0.4064)
			(stroke
				(width 0.1524)
				(type default)
			)
			(layer "F.SilkS")
		)
		(fp_line
			(start -0.7874 -0.4064)
			(end 0.7874 -0.4064)
			(stroke
				(width 0.1524)
				(type default)
			)
			(layer "F.SilkS")
		)
		(fp_line
			(start 0.67945 0.3048)
			(end 0.120396 0.3048)
			(stroke
				(width 0.1)
				(type default)
			)
			(layer "F.Fab")
		)
		(fp_line
			(start 0.67945 -0.3048)
			(end 0.67945 0.3048)
			(stroke
				(width 0.1)
				(type default)
			)
			(layer "F.Fab")
		)
		(fp_line
			(start 0.12065 -0.2794)
			(end 0.12065 -0.3048)
			(stroke
				(width 0.1)
				(type default)
			)
			(layer "F.Fab")
		)
		(fp_line
			(start 0.12065 -0.3048)
			(end 0.67945 -0.3048)
			(stroke
				(width 0.1)
				(type default)
			)
			(layer "F.Fab")
		)
		(fp_line
			(start 0.120396 0.3048)
			(end 0.120396 0.2794)
			(stroke
				(width 0.1)
				(type default)
			)
			(layer "F.Fab")
		)
		(fp_line
			(start 0.120396 0.2794)
			(end -0.12065 0.2794)
			(stroke
				(width 0.1)
				(type default)
			)
			(layer "F.Fab")
		)
		(fp_line
			(start -0.12065 0.3048)
			(end -0.67945 0.3048)
			(stroke
				(width 0.1)
				(type default)
			)
			(layer "F.Fab")
		)
		(fp_line
			(start -0.12065 0.2794)
			(end -0.12065 0.3048)
			(stroke
				(width 0.1)
				(type default)
			)
			(layer "F.Fab")
		)
		(fp_line
			(start -0.12065 -0.2794)
			(end 0.12065 -0.2794)
			(stroke
				(width 0.1)
				(type default)
			)
			(layer "F.Fab")
		)
		(fp_line
			(start -0.12065 -0.305054)
			(end -0.12065 -0.2794)
			(stroke
				(width 0.1)
				(type default)
			)
			(layer "F.Fab")
		)
		(fp_line
			(start -0.67945 0.3048)
			(end -0.67945 -0.305054)
			(stroke
				(width 0.1)
				(type default)
			)
			(layer "F.Fab")
		)
		(fp_line
			(start -0.67945 -0.305054)
			(end -0.12065 -0.305054)
			(stroke
				(width 0.1)
				(type default)
			)
			(layer "F.Fab")
		)
		(pad "1" smd circle
			(at -0.40005 0 180)
			(size 0 0)
			(layers "F.Cu" "F.Mask" "F.Paste")
			(net "P3V3_NIC2")
		)
		(pad "2" smd circle
			(at 0.40005 0 180)
			(size 0 0)
			(layers "F.Cu" "F.Mask" "F.Paste")
			(net "GND")
		)
	)
	(footprint ""
		(layer "F.Cu")
		(at 123.67514 -94.891606)
		(property "Reference" "R1579"
			(at 0 0 0)
			(layer "F.SilkS")
			(hide yes)
			(effects
				(font
					(size 1.27 1.27)
				)
			)
		)
		(property "Value" ""
			(at 0 0 0)
			(layer "F.Fab")
			(effects
				(font
					(size 1.27 1.27)
				)
			)
		)
		(duplicate_pad_numbers_are_jumpers no)
		(fp_line
			(start -0.7874 -0.4064)
			(end 0.7874 -0.4064)
			(stroke
				(width 0.1524)
				(type default)
			)
			(layer "F.SilkS")
		)
		(fp_line
			(start -0.7874 0.4064)
			(end -0.7874 -0.4064)
			(stroke
				(width 0.1524)
				(type default)
			)
			(layer "F.SilkS")
		)
		(fp_line
			(start 0.7874 -0.4064)
			(end 0.7874 0.4064)
			(stroke
				(width 0.1524)
				(type default)
			)
			(layer "F.SilkS")
		)
		(fp_line
			(start 0.7874 0.4064)
			(end -0.7874 0.4064)
			(stroke
				(width 0.1524)
				(type default)
			)
			(layer "F.SilkS")
		)
		(fp_line
			(start -0.67945 -0.305054)
			(end -0.12065 -0.305054)
			(stroke
				(width 0.1)
				(type default)
			)
			(layer "F.Fab")
		)
		(fp_line
			(start -0.67945 0.3048)
			(end -0.67945 -0.305054)
			(stroke
				(width 0.1)
				(type default)
			)
			(layer "F.Fab")
		)
		(fp_line
			(start -0.12065 -0.305054)
			(end -0.12065 -0.2794)
			(stroke
				(width 0.1)
				(type default)
			)
			(layer "F.Fab")
		)
		(fp_line
			(start -0.12065 -0.2794)
			(end 0.12065 -0.2794)
			(stroke
				(width 0.1)
				(type default)
			)
			(layer "F.Fab")
		)
		(fp_line
			(start -0.12065 0.2794)
			(end -0.12065 0.3048)
			(stroke
				(width 0.1)
				(type default)
			)
			(layer "F.Fab")
		)
		(fp_line
			(start -0.12065 0.3048)
			(end -0.67945 0.3048)
			(stroke
				(width 0.1)
				(type default)
			)
			(layer "F.Fab")
		)
		(fp_line
			(start 0.120396 0.2794)
			(end -0.12065 0.2794)
			(stroke
				(width 0.1)
				(type default)
			)
			(layer "F.Fab")
		)
		(fp_line
			(start 0.120396 0.3048)
			(end 0.120396 0.2794)
			(stroke
				(width 0.1)
				(type default)
			)
			(layer "F.Fab")
		)
		(fp_line
			(start 0.12065 -0.3048)
			(end 0.67945 -0.3048)
			(stroke
				(width 0.1)
				(type default)
			)
			(layer "F.Fab")
		)
		(fp_line
			(start 0.12065 -0.2794)
			(end 0.12065 -0.3048)
			(stroke
				(width 0.1)
				(type default)
			)
			(layer "F.Fab")
		)
		(fp_line
			(start 0.67945 -0.3048)
			(end 0.67945 0.3048)
			(stroke
				(width 0.1)
				(type default)
			)
			(layer "F.Fab")
		)
		(fp_line
			(start 0.67945 0.3048)
			(end 0.120396 0.3048)
			(stroke
				(width 0.1)
				(type default)
			)
			(layer "F.Fab")
		)
		(pad "1" smd circle
			(at -0.40005 0)
			(size 0 0)
			(layers "F.Cu" "F.Mask" "F.Paste")
			(net "SMB_BIC_I2C9_MUX0_SSD1_R_SDA")
		)
		(pad "2" smd circle
			(at 0.40005 0)
			(size 0 0)
			(layers "F.Cu" "F.Mask" "F.Paste")
			(net "SMB_BIC_I2C9_MUX0_SSD1_SDA")
		)
	)
	(footprint ""
		(layer "F.Cu")
		(at 120.974358 -279.101804)
		(property "Reference" "PC91"
			(at 0 0 0)
			(layer "F.SilkS")
			(hide yes)
			(effects
				(font
					(size 1.27 1.27)
				)
			)
		)
		(property "Value" ""
			(at 0 0 0)
			(layer "F.Fab")
			(effects
				(font
					(size 1.27 1.27)
				)
			)
		)
		(duplicate_pad_numbers_are_jumpers no)
		(fp_line
			(start -0.7874 -0.4064)
			(end 0.7874 -0.4064)
			(stroke
				(width 0.1524)
				(type default)
			)
			(layer "F.SilkS")
		)
		(fp_line
			(start -0.7874 0.4064)
			(end -0.7874 -0.4064)
			(stroke
				(width 0.1524)
				(type default)
			)
			(layer "F.SilkS")
		)
		(fp_line
			(start 0.7874 -0.4064)
			(end 0.7874 0.4064)
			(stroke
				(width 0.1524)
				(type default)
			)
			(layer "F.SilkS")
		)
		(fp_line
			(start 0.7874 0.4064)
			(end -0.7874 0.4064)
			(stroke
				(width 0.1524)
				(type default)
			)
			(layer "F.SilkS")
		)
		(fp_line
			(start -0.67945 -0.305054)
			(end -0.12065 -0.305054)
			(stroke
				(width 0.1)
				(type default)
			)
			(layer "F.Fab")
		)
		(fp_line
			(start -0.67945 0.3048)
			(end -0.67945 -0.305054)
			(stroke
				(width 0.1)
				(type default)
			)
			(layer "F.Fab")
		)
		(fp_line
			(start -0.12065 -0.305054)
			(end -0.12065 -0.2794)
			(stroke
				(width 0.1)
				(type default)
			)
			(layer "F.Fab")
		)
		(fp_line
			(start -0.12065 -0.2794)
			(end 0.12065 -0.2794)
			(stroke
				(width 0.1)
				(type default)
			)
			(layer "F.Fab")
		)
		(fp_line
			(start -0.12065 0.2794)
			(end -0.12065 0.3048)
			(stroke
				(width 0.1)
				(type default)
			)
			(layer "F.Fab")
		)
		(fp_line
			(start -0.12065 0.3048)
			(end -0.67945 0.3048)
			(stroke
				(width 0.1)
				(type default)
			)
			(layer "F.Fab")
		)
		(fp_line
			(start 0.120396 0.2794)
			(end -0.12065 0.2794)
			(stroke
				(width 0.1)
				(type default)
			)
			(layer "F.Fab")
		)
		(fp_line
			(start 0.120396 0.3048)
			(end 0.120396 0.2794)
			(stroke
				(width 0.1)
				(type default)
			)
			(layer "F.Fab")
		)
		(fp_line
			(start 0.12065 -0.3048)
			(end 0.67945 -0.3048)
			(stroke
				(width 0.1)
				(type default)
			)
			(layer "F.Fab")
		)
		(fp_line
			(start 0.12065 -0.2794)
			(end 0.12065 -0.3048)
			(stroke
				(width 0.1)
				(type default)
			)
			(layer "F.Fab")
		)
		(fp_line
			(start 0.67945 -0.3048)
			(end 0.67945 0.3048)
			(stroke
				(width 0.1)
				(type default)
			)
			(layer "F.Fab")
		)
		(fp_line
			(start 0.67945 0.3048)
			(end 0.120396 0.3048)
			(stroke
				(width 0.1)
				(type default)
			)
			(layer "F.Fab")
		)
		(pad "1" smd circle
			(at -0.40005 0)
			(size 0 0)
			(layers "F.Cu" "F.Mask" "F.Paste")
			(net "SW_P12V_P0V8_PEX1_FLT")
		)
		(pad "2" smd circle
			(at 0.40005 0)
			(size 0 0)
			(layers "F.Cu" "F.Mask" "F.Paste")
			(net "GND")
		)
	)
	(footprint ""
		(layer "F.Cu")
		(at 313.557666 -27.006296 -90)
		(property "Reference" "PR7121"
			(at 0 0 270)
			(layer "F.SilkS")
			(hide yes)
			(effects
				(font
					(size 1.27 1.27)
				)
			)
		)
		(property "Value" ""
			(at 0 0 270)
			(layer "F.Fab")
			(effects
				(font
					(size 1.27 1.27)
				)
			)
		)
		(duplicate_pad_numbers_are_jumpers no)
		(fp_line
			(start -0.7874 0.4064)
			(end -0.7874 -0.4064)
			(stroke
				(width 0.1524)
				(type default)
			)
			(layer "F.SilkS")
		)
		(fp_line
			(start 0.7874 0.4064)
			(end -0.7874 0.4064)
			(stroke
				(width 0.1524)
				(type default)
			)
			(layer "F.SilkS")
		)
		(fp_line
			(start -0.7874 -0.4064)
			(end 0.7874 -0.4064)
			(stroke
				(width 0.1524)
				(type default)
			)
			(layer "F.SilkS")
		)
		(fp_line
			(start 0.7874 -0.4064)
			(end 0.7874 0.4064)
			(stroke
				(width 0.1524)
				(type default)
			)
			(layer "F.SilkS")
		)
		(fp_line
			(start -0.67945 0.3048)
			(end -0.67945 -0.305054)
			(stroke
				(width 0.1)
				(type default)
			)
			(layer "F.Fab")
		)
		(fp_line
			(start -0.12065 0.3048)
			(end -0.67945 0.3048)
			(stroke
				(width 0.1)
				(type default)
			)
			(layer "F.Fab")
		)
		(fp_line
			(start 0.120396 0.3048)
			(end 0.120396 0.2794)
			(stroke
				(width 0.1)
				(type default)
			)
			(layer "F.Fab")
		)
		(fp_line
			(start 0.67945 0.3048)
			(end 0.120396 0.3048)
			(stroke
				(width 0.1)
				(type default)
			)
			(layer "F.Fab")
		)
		(fp_line
			(start -0.12065 0.2794)
			(end -0.12065 0.3048)
			(stroke
				(width 0.1)
				(type default)
			)
			(layer "F.Fab")
		)
		(fp_line
			(start 0.120396 0.2794)
			(end -0.12065 0.2794)
			(stroke
				(width 0.1)
				(type default)
			)
			(layer "F.Fab")
		)
		(fp_line
			(start -0.12065 -0.2794)
			(end 0.12065 -0.2794)
			(stroke
				(width 0.1)
				(type default)
			)
			(layer "F.Fab")
		)
		(fp_line
			(start 0.12065 -0.2794)
			(end 0.12065 -0.3048)
			(stroke
				(width 0.1)
				(type default)
			)
			(layer "F.Fab")
		)
		(fp_line
			(start 0.12065 -0.3048)
			(end 0.67945 -0.3048)
			(stroke
				(width 0.1)
				(type default)
			)
			(layer "F.Fab")
		)
		(fp_line
			(start 0.67945 -0.3048)
			(end 0.67945 0.3048)
			(stroke
				(width 0.1)
				(type default)
			)
			(layer "F.Fab")
		)
		(fp_line
			(start -0.67945 -0.305054)
			(end -0.12065 -0.305054)
			(stroke
				(width 0.1)
				(type default)
			)
			(layer "F.Fab")
		)
		(fp_line
			(start -0.12065 -0.305054)
			(end -0.12065 -0.2794)
			(stroke
				(width 0.1)
				(type default)
			)
			(layer "F.Fab")
		)
		(pad "1" smd circle
			(at -0.40005 0 270)
			(size 0 0)
			(layers "F.Cu" "F.Mask" "F.Paste")
			(net "P3V3_SSD11_CO_MODE")
		)
		(pad "2" smd circle
			(at 0.40005 0 270)
			(size 0 0)
			(layers "F.Cu" "F.Mask" "F.Paste")
			(net "GND")
		)
	)
	(footprint ""
		(layer "F.Cu")
		(at 373.658384 -250.070874 -90)
		(property "Reference" "R1412"
			(at 0 0 270)
			(layer "F.SilkS")
			(hide yes)
			(effects
				(font
					(size 1.27 1.27)
				)
			)
		)
		(property "Value" ""
			(at 0 0 270)
			(layer "F.Fab")
			(effects
				(font
					(size 1.27 1.27)
				)
			)
		)
		(duplicate_pad_numbers_are_jumpers no)
		(fp_line
			(start -0.7874 0.4064)
			(end -0.7874 -0.4064)
			(stroke
				(width 0.1524)
				(type default)
			)
			(layer "F.SilkS")
		)
		(fp_line
			(start 0.7874 0.4064)
			(end -0.7874 0.4064)
			(stroke
				(width 0.1524)
				(type default)
			)
			(layer "F.SilkS")
		)
		(fp_line
			(start -0.7874 -0.4064)
			(end 0.7874 -0.4064)
			(stroke
				(width 0.1524)
				(type default)
			)
			(layer "F.SilkS")
		)
		(fp_line
			(start 0.7874 -0.4064)
			(end 0.7874 0.4064)
			(stroke
				(width 0.1524)
				(type default)
			)
			(layer "F.SilkS")
		)
		(fp_line
			(start -0.67945 0.3048)
			(end -0.67945 -0.305054)
			(stroke
				(width 0.1)
				(type default)
			)
			(layer "F.Fab")
		)
		(fp_line
			(start -0.12065 0.3048)
			(end -0.67945 0.3048)
			(stroke
				(width 0.1)
				(type default)
			)
			(layer "F.Fab")
		)
		(fp_line
			(start 0.120396 0.3048)
			(end 0.120396 0.2794)
			(stroke
				(width 0.1)
				(type default)
			)
			(layer "F.Fab")
		)
		(fp_line
			(start 0.67945 0.3048)
			(end 0.120396 0.3048)
			(stroke
				(width 0.1)
				(type default)
			)
			(layer "F.Fab")
		)
		(fp_line
			(start -0.12065 0.2794)
			(end -0.12065 0.3048)
			(stroke
				(width 0.1)
				(type default)
			)
			(layer "F.Fab")
		)
		(fp_line
			(start 0.120396 0.2794)
			(end -0.12065 0.2794)
			(stroke
				(width 0.1)
				(type default)
			)
			(layer "F.Fab")
		)
		(fp_line
			(start -0.12065 -0.2794)
			(end 0.12065 -0.2794)
			(stroke
				(width 0.1)
				(type default)
			)
			(layer "F.Fab")
		)
		(fp_line
			(start 0.12065 -0.2794)
			(end 0.12065 -0.3048)
			(stroke
				(width 0.1)
				(type default)
			)
			(layer "F.Fab")
		)
		(fp_line
			(start 0.12065 -0.3048)
			(end 0.67945 -0.3048)
			(stroke
				(width 0.1)
				(type default)
			)
			(layer "F.Fab")
		)
		(fp_line
			(start 0.67945 -0.3048)
			(end 0.67945 0.3048)
			(stroke
				(width 0.1)
				(type default)
			)
			(layer "F.Fab")
		)
		(fp_line
			(start -0.67945 -0.305054)
			(end -0.12065 -0.305054)
			(stroke
				(width 0.1)
				(type default)
			)
			(layer "F.Fab")
		)
		(fp_line
			(start -0.12065 -0.305054)
			(end -0.12065 -0.2794)
			(stroke
				(width 0.1)
				(type default)
			)
			(layer "F.Fab")
		)
		(pad "1" smd circle
			(at -0.40005 0 270)
			(size 0 0)
			(layers "F.Cu" "F.Mask" "F.Paste")
			(net "PEX3_MODE_SEL7")
		)
		(pad "2" smd circle
			(at 0.40005 0 270)
			(size 0 0)
			(layers "F.Cu" "F.Mask" "F.Paste")
			(net "P1V8_PEX")
		)
	)
)
